(kicad_pcb
	(version 20260206)
	(generator "pcbnew")
	(generator_version "10.0")
	(general
		(thickness 1.6)
		(legacy_teardrops no)
	)
	(paper "A4")
	(title_block
		(title "12092022_DA0F0TMDCD0_F0T_Management_Board_D_brd_V3_OCP.brd")
		(comment 1 "Grand Teton / footprints 951-956 of 1440")
	)
	(layers
		(0 "F.Cu" signal "TOP")
		(4 "In1.Cu" signal "GND")
		(6 "In2.Cu" signal "IN1")
		(8 "In3.Cu" signal "GND1")
		(10 "In4.Cu" signal "IN2")
		(12 "In5.Cu" signal "VCC")
		(14 "In6.Cu" signal "VCC1")
		(16 "In7.Cu" signal "IN3")
		(18 "In8.Cu" signal "GND2")
		(20 "In9.Cu" signal "IN4")
		(22 "In10.Cu" signal "GND3")
		(2 "B.Cu" signal "BOTTOM")
		(9 "F.Adhes" user "F.Adhesive")
		(11 "B.Adhes" user "B.Adhesive")
		(13 "F.Paste" user "Package Geometry/Pastemask Top")
		(15 "B.Paste" user "Package Geometry/Pastemask Bottom")
		(5 "F.SilkS" user "Ref Des/Silkscreen Top")
		(7 "B.SilkS" user "Ref Des/Silkscreen Bottom")
		(1 "F.Mask" user "Board Geometry/Soldermask Top")
		(3 "B.Mask" user "Board Geometry/Soldermask Bottom")
		(17 "Dwgs.User" user "User.Drawings")
		(19 "Cmts.User" user "User.Comments")
		(21 "Eco1.User" user "User.Eco1")
		(23 "Eco2.User" user "User.Eco2")
		(25 "Edge.Cuts" user "Board Geometry/Outline")
		(27 "Margin" user)
		(31 "F.CrtYd" user "Package Geometry/Place Bound Top")
		(29 "B.CrtYd" user "Package Geometry/Place Bound Bottom")
		(35 "F.Fab" user "Ref Des/Assembly Top")
		(33 "B.Fab" user "Ref Des/Assembly Bottom")
	)
	(footprint ""
		(layer "B.Cu")
		(at 56.256174 -44.791884)
		(property "Reference" "C95"
			(at 0 0 0)
			(layer "B.SilkS")
			(hide yes)
			(effects
				(font
					(size 1.27 1.27)
				)
				(justify mirror)
			)
		)
		(property "Value" ""
			(at 0 0 0)
			(layer "B.Fab")
			(effects
				(font
					(size 1.27 1.27)
				)
				(justify mirror)
			)
		)
		(duplicate_pad_numbers_are_jumpers no)
		(fp_line
			(start -0.7874 -0.4064)
			(end -0.7874 0.4064)
			(stroke
				(width 0.1524)
				(type default)
			)
			(layer "B.SilkS")
		)
		(fp_line
			(start -0.7874 0.4064)
			(end 0.7874 0.4064)
			(stroke
				(width 0.1524)
				(type default)
			)
			(layer "B.SilkS")
		)
		(fp_line
			(start 0.7874 -0.4064)
			(end -0.7874 -0.4064)
			(stroke
				(width 0.1524)
				(type default)
			)
			(layer "B.SilkS")
		)
		(fp_line
			(start 0.7874 0.4064)
			(end 0.7874 -0.4064)
			(stroke
				(width 0.1524)
				(type default)
			)
			(layer "B.SilkS")
		)
		(fp_line
			(start -0.67945 -0.3048)
			(end -0.67945 0.3048)
			(stroke
				(width 0.1)
				(type default)
			)
			(layer "B.Fab")
		)
		(fp_line
			(start -0.67945 0.3048)
			(end -0.120396 0.3048)
			(stroke
				(width 0.1)
				(type default)
			)
			(layer "B.Fab")
		)
		(fp_line
			(start -0.12065 -0.3048)
			(end -0.67945 -0.3048)
			(stroke
				(width 0.1)
				(type default)
			)
			(layer "B.Fab")
		)
		(fp_line
			(start -0.12065 -0.2794)
			(end -0.12065 -0.3048)
			(stroke
				(width 0.1)
				(type default)
			)
			(layer "B.Fab")
		)
		(fp_line
			(start -0.120396 0.2794)
			(end 0.12065 0.2794)
			(stroke
				(width 0.1)
				(type default)
			)
			(layer "B.Fab")
		)
		(fp_line
			(start -0.120396 0.3048)
			(end -0.120396 0.2794)
			(stroke
				(width 0.1)
				(type default)
			)
			(layer "B.Fab")
		)
		(fp_line
			(start 0.12065 -0.305054)
			(end 0.12065 -0.2794)
			(stroke
				(width 0.1)
				(type default)
			)
			(layer "B.Fab")
		)
		(fp_line
			(start 0.12065 -0.2794)
			(end -0.12065 -0.2794)
			(stroke
				(width 0.1)
				(type default)
			)
			(layer "B.Fab")
		)
		(fp_line
			(start 0.12065 0.2794)
			(end 0.12065 0.3048)
			(stroke
				(width 0.1)
				(type default)
			)
			(layer "B.Fab")
		)
		(fp_line
			(start 0.12065 0.3048)
			(end 0.67945 0.3048)
			(stroke
				(width 0.1)
				(type default)
			)
			(layer "B.Fab")
		)
		(fp_line
			(start 0.67945 -0.305054)
			(end 0.12065 -0.305054)
			(stroke
				(width 0.1)
				(type default)
			)
			(layer "B.Fab")
		)
		(fp_line
			(start 0.67945 0.3048)
			(end 0.67945 -0.305054)
			(stroke
				(width 0.1)
				(type default)
			)
			(layer "B.Fab")
		)
		(pad "1" smd circle
			(at 0.40005 0 180)
			(size 0 0)
			(layers "B.Cu" "B.Mask" "B.Paste")
			(net "P1V8_AUX")
		)
		(pad "2" smd circle
			(at -0.40005 0 180)
			(size 0 0)
			(layers "B.Cu" "B.Mask" "B.Paste")
			(net "GND")
		)
	)
	(footprint ""
		(layer "B.Cu")
		(at 42.350182 -30.816804 -90)
		(property "Reference" "R246"
			(at 0 0 90)
			(layer "B.SilkS")
			(hide yes)
			(effects
				(font
					(size 1.27 1.27)
				)
				(justify mirror)
			)
		)
		(property "Value" ""
			(at 0 0 90)
			(layer "B.Fab")
			(effects
				(font
					(size 1.27 1.27)
				)
				(justify mirror)
			)
		)
		(duplicate_pad_numbers_are_jumpers no)
		(fp_line
			(start -0.7874 0.4064)
			(end 0.7874 0.4064)
			(stroke
				(width 0.1524)
				(type default)
			)
			(layer "B.SilkS")
		)
		(fp_line
			(start 0.7874 0.4064)
			(end 0.7874 -0.4064)
			(stroke
				(width 0.1524)
				(type default)
			)
			(layer "B.SilkS")
		)
		(fp_line
			(start -0.7874 -0.4064)
			(end -0.7874 0.4064)
			(stroke
				(width 0.1524)
				(type default)
			)
			(layer "B.SilkS")
		)
		(fp_line
			(start 0.7874 -0.4064)
			(end -0.7874 -0.4064)
			(stroke
				(width 0.1524)
				(type default)
			)
			(layer "B.SilkS")
		)
		(fp_line
			(start -0.67945 0.3048)
			(end -0.120396 0.3048)
			(stroke
				(width 0.1)
				(type default)
			)
			(layer "B.Fab")
		)
		(fp_line
			(start -0.120396 0.3048)
			(end -0.120396 0.2794)
			(stroke
				(width 0.1)
				(type default)
			)
			(layer "B.Fab")
		)
		(fp_line
			(start 0.12065 0.3048)
			(end 0.67945 0.3048)
			(stroke
				(width 0.1)
				(type default)
			)
			(layer "B.Fab")
		)
		(fp_line
			(start 0.67945 0.3048)
			(end 0.67945 -0.305054)
			(stroke
				(width 0.1)
				(type default)
			)
			(layer "B.Fab")
		)
		(fp_line
			(start -0.120396 0.2794)
			(end 0.12065 0.2794)
			(stroke
				(width 0.1)
				(type default)
			)
			(layer "B.Fab")
		)
		(fp_line
			(start 0.12065 0.2794)
			(end 0.12065 0.3048)
			(stroke
				(width 0.1)
				(type default)
			)
			(layer "B.Fab")
		)
		(fp_line
			(start -0.12065 -0.2794)
			(end -0.12065 -0.3048)
			(stroke
				(width 0.1)
				(type default)
			)
			(layer "B.Fab")
		)
		(fp_line
			(start 0.12065 -0.2794)
			(end -0.12065 -0.2794)
			(stroke
				(width 0.1)
				(type default)
			)
			(layer "B.Fab")
		)
		(fp_line
			(start -0.67945 -0.3048)
			(end -0.67945 0.3048)
			(stroke
				(width 0.1)
				(type default)
			)
			(layer "B.Fab")
		)
		(fp_line
			(start -0.12065 -0.3048)
			(end -0.67945 -0.3048)
			(stroke
				(width 0.1)
				(type default)
			)
			(layer "B.Fab")
		)
		(fp_line
			(start 0.12065 -0.305054)
			(end 0.12065 -0.2794)
			(stroke
				(width 0.1)
				(type default)
			)
			(layer "B.Fab")
		)
		(fp_line
			(start 0.67945 -0.305054)
			(end 0.12065 -0.305054)
			(stroke
				(width 0.1)
				(type default)
			)
			(layer "B.Fab")
		)
		(pad "1" smd circle
			(at 0.40005 0 90)
			(size 0 0)
			(layers "B.Cu" "B.Mask" "B.Paste")
			(net "P3V3_AUX")
		)
		(pad "2" smd circle
			(at -0.40005 0 90)
			(size 0 0)
			(layers "B.Cu" "B.Mask" "B.Paste")
			(net "SMB_BMC_MM2_SCL")
		)
	)
	(footprint ""
		(layer "B.Cu")
		(at 65.405 -69.977 90)
		(property "Reference" "R312"
			(at 0 0 90)
			(layer "B.SilkS")
			(hide yes)
			(effects
				(font
					(size 1.27 1.27)
				)
				(justify mirror)
			)
		)
		(property "Value" ""
			(at 0 0 90)
			(layer "B.Fab")
			(effects
				(font
					(size 1.27 1.27)
				)
				(justify mirror)
			)
		)
		(duplicate_pad_numbers_are_jumpers no)
		(fp_line
			(start 0.7874 -0.4064)
			(end -0.7874 -0.4064)
			(stroke
				(width 0.1524)
				(type default)
			)
			(layer "B.SilkS")
		)
		(fp_line
			(start -0.7874 -0.4064)
			(end -0.7874 0.4064)
			(stroke
				(width 0.1524)
				(type default)
			)
			(layer "B.SilkS")
		)
		(fp_line
			(start 0.7874 0.4064)
			(end 0.7874 -0.4064)
			(stroke
				(width 0.1524)
				(type default)
			)
			(layer "B.SilkS")
		)
		(fp_line
			(start -0.7874 0.4064)
			(end 0.7874 0.4064)
			(stroke
				(width 0.1524)
				(type default)
			)
			(layer "B.SilkS")
		)
		(fp_line
			(start 0.67945 -0.305054)
			(end 0.12065 -0.305054)
			(stroke
				(width 0.1)
				(type default)
			)
			(layer "B.Fab")
		)
		(fp_line
			(start 0.12065 -0.305054)
			(end 0.12065 -0.2794)
			(stroke
				(width 0.1)
				(type default)
			)
			(layer "B.Fab")
		)
		(fp_line
			(start -0.12065 -0.3048)
			(end -0.67945 -0.3048)
			(stroke
				(width 0.1)
				(type default)
			)
			(layer "B.Fab")
		)
		(fp_line
			(start -0.67945 -0.3048)
			(end -0.67945 0.3048)
			(stroke
				(width 0.1)
				(type default)
			)
			(layer "B.Fab")
		)
		(fp_line
			(start 0.12065 -0.2794)
			(end -0.12065 -0.2794)
			(stroke
				(width 0.1)
				(type default)
			)
			(layer "B.Fab")
		)
		(fp_line
			(start -0.12065 -0.2794)
			(end -0.12065 -0.3048)
			(stroke
				(width 0.1)
				(type default)
			)
			(layer "B.Fab")
		)
		(fp_line
			(start 0.12065 0.2794)
			(end 0.12065 0.3048)
			(stroke
				(width 0.1)
				(type default)
			)
			(layer "B.Fab")
		)
		(fp_line
			(start -0.120396 0.2794)
			(end 0.12065 0.2794)
			(stroke
				(width 0.1)
				(type default)
			)
			(layer "B.Fab")
		)
		(fp_line
			(start 0.67945 0.3048)
			(end 0.67945 -0.305054)
			(stroke
				(width 0.1)
				(type default)
			)
			(layer "B.Fab")
		)
		(fp_line
			(start 0.12065 0.3048)
			(end 0.67945 0.3048)
			(stroke
				(width 0.1)
				(type default)
			)
			(layer "B.Fab")
		)
		(fp_line
			(start -0.120396 0.3048)
			(end -0.120396 0.2794)
			(stroke
				(width 0.1)
				(type default)
			)
			(layer "B.Fab")
		)
		(fp_line
			(start -0.67945 0.3048)
			(end -0.120396 0.3048)
			(stroke
				(width 0.1)
				(type default)
			)
			(layer "B.Fab")
		)
		(pad "1" smd circle
			(at 0.40005 0 270)
			(size 0 0)
			(layers "B.Cu" "B.Mask" "B.Paste")
			(net "RST_BMC_LPC_ESPI_N")
		)
		(pad "2" smd circle
			(at -0.40005 0 270)
			(size 0 0)
			(layers "B.Cu" "B.Mask" "B.Paste")
			(net "GND")
		)
	)
	(footprint ""
		(layer "B.Cu")
		(at 59.662822 -72.113394)
		(property "Reference" "R797"
			(at 0 0 0)
			(layer "B.SilkS")
			(hide yes)
			(effects
				(font
					(size 1.27 1.27)
				)
				(justify mirror)
			)
		)
		(property "Value" ""
			(at 0 0 0)
			(layer "B.Fab")
			(effects
				(font
					(size 1.27 1.27)
				)
				(justify mirror)
			)
		)
		(duplicate_pad_numbers_are_jumpers no)
		(fp_line
			(start -0.7874 -0.4064)
			(end -0.7874 0.4064)
			(stroke
				(width 0.1524)
				(type default)
			)
			(layer "B.SilkS")
		)
		(fp_line
			(start -0.7874 0.4064)
			(end 0.7874 0.4064)
			(stroke
				(width 0.1524)
				(type default)
			)
			(layer "B.SilkS")
		)
		(fp_line
			(start 0.7874 -0.4064)
			(end -0.7874 -0.4064)
			(stroke
				(width 0.1524)
				(type default)
			)
			(layer "B.SilkS")
		)
		(fp_line
			(start 0.7874 0.4064)
			(end 0.7874 -0.4064)
			(stroke
				(width 0.1524)
				(type default)
			)
			(layer "B.SilkS")
		)
		(fp_line
			(start -0.67945 -0.3048)
			(end -0.67945 0.3048)
			(stroke
				(width 0.1)
				(type default)
			)
			(layer "B.Fab")
		)
		(fp_line
			(start -0.67945 0.3048)
			(end -0.120396 0.3048)
			(stroke
				(width 0.1)
				(type default)
			)
			(layer "B.Fab")
		)
		(fp_line
			(start -0.12065 -0.3048)
			(end -0.67945 -0.3048)
			(stroke
				(width 0.1)
				(type default)
			)
			(layer "B.Fab")
		)
		(fp_line
			(start -0.12065 -0.2794)
			(end -0.12065 -0.3048)
			(stroke
				(width 0.1)
				(type default)
			)
			(layer "B.Fab")
		)
		(fp_line
			(start -0.120396 0.2794)
			(end 0.12065 0.2794)
			(stroke
				(width 0.1)
				(type default)
			)
			(layer "B.Fab")
		)
		(fp_line
			(start -0.120396 0.3048)
			(end -0.120396 0.2794)
			(stroke
				(width 0.1)
				(type default)
			)
			(layer "B.Fab")
		)
		(fp_line
			(start 0.12065 -0.305054)
			(end 0.12065 -0.2794)
			(stroke
				(width 0.1)
				(type default)
			)
			(layer "B.Fab")
		)
		(fp_line
			(start 0.12065 -0.2794)
			(end -0.12065 -0.2794)
			(stroke
				(width 0.1)
				(type default)
			)
			(layer "B.Fab")
		)
		(fp_line
			(start 0.12065 0.2794)
			(end 0.12065 0.3048)
			(stroke
				(width 0.1)
				(type default)
			)
			(layer "B.Fab")
		)
		(fp_line
			(start 0.12065 0.3048)
			(end 0.67945 0.3048)
			(stroke
				(width 0.1)
				(type default)
			)
			(layer "B.Fab")
		)
		(fp_line
			(start 0.67945 -0.305054)
			(end 0.12065 -0.305054)
			(stroke
				(width 0.1)
				(type default)
			)
			(layer "B.Fab")
		)
		(fp_line
			(start 0.67945 0.3048)
			(end 0.67945 -0.305054)
			(stroke
				(width 0.1)
				(type default)
			)
			(layer "B.Fab")
		)
		(pad "1" smd circle
			(at 0.40005 0 180)
			(size 0 0)
			(layers "B.Cu" "B.Mask" "B.Paste")
			(net "PGPPA_BMC_AUX")
		)
		(pad "2" smd circle
			(at -0.40005 0 180)
			(size 0 0)
			(layers "B.Cu" "B.Mask" "B.Paste")
			(net "PGPPA_BMC_AUX_SENSOR")
		)
	)
	(footprint ""
		(layer "B.Cu")
		(at 85.29955 -40.363394 180)
		(property "Reference" "R352"
			(at 0 0 0)
			(layer "B.SilkS")
			(hide yes)
			(effects
				(font
					(size 1.27 1.27)
				)
				(justify mirror)
			)
		)
		(property "Value" ""
			(at 0 0 0)
			(layer "B.Fab")
			(effects
				(font
					(size 1.27 1.27)
				)
				(justify mirror)
			)
		)
		(duplicate_pad_numbers_are_jumpers no)
		(fp_line
			(start 0.7874 0.4064)
			(end 0.7874 -0.4064)
			(stroke
				(width 0.1524)
				(type default)
			)
			(layer "B.SilkS")
		)
		(fp_line
			(start 0.7874 -0.4064)
			(end -0.7874 -0.4064)
			(stroke
				(width 0.1524)
				(type default)
			)
			(layer "B.SilkS")
		)
		(fp_line
			(start -0.7874 0.4064)
			(end 0.7874 0.4064)
			(stroke
				(width 0.1524)
				(type default)
			)
			(layer "B.SilkS")
		)
		(fp_line
			(start -0.7874 -0.4064)
			(end -0.7874 0.4064)
			(stroke
				(width 0.1524)
				(type default)
			)
			(layer "B.SilkS")
		)
		(fp_line
			(start 0.67945 0.3048)
			(end 0.67945 -0.305054)
			(stroke
				(width 0.1)
				(type default)
			)
			(layer "B.Fab")
		)
		(fp_line
			(start 0.67945 -0.305054)
			(end 0.12065 -0.305054)
			(stroke
				(width 0.1)
				(type default)
			)
			(layer "B.Fab")
		)
		(fp_line
			(start 0.12065 0.3048)
			(end 0.67945 0.3048)
			(stroke
				(width 0.1)
				(type default)
			)
			(layer "B.Fab")
		)
		(fp_line
			(start 0.12065 0.2794)
			(end 0.12065 0.3048)
			(stroke
				(width 0.1)
				(type default)
			)
			(layer "B.Fab")
		)
		(fp_line
			(start 0.12065 -0.2794)
			(end -0.12065 -0.2794)
			(stroke
				(width 0.1)
				(type default)
			)
			(layer "B.Fab")
		)
		(fp_line
			(start 0.12065 -0.305054)
			(end 0.12065 -0.2794)
			(stroke
				(width 0.1)
				(type default)
			)
			(layer "B.Fab")
		)
		(fp_line
			(start -0.120396 0.3048)
			(end -0.120396 0.2794)
			(stroke
				(width 0.1)
				(type default)
			)
			(layer "B.Fab")
		)
		(fp_line
			(start -0.120396 0.2794)
			(end 0.12065 0.2794)
			(stroke
				(width 0.1)
				(type default)
			)
			(layer "B.Fab")
		)
		(fp_line
			(start -0.12065 -0.2794)
			(end -0.12065 -0.3048)
			(stroke
				(width 0.1)
				(type default)
			)
			(layer "B.Fab")
		)
		(fp_line
			(start -0.12065 -0.3048)
			(end -0.67945 -0.3048)
			(stroke
				(width 0.1)
				(type default)
			)
			(layer "B.Fab")
		)
		(fp_line
			(start -0.67945 0.3048)
			(end -0.120396 0.3048)
			(stroke
				(width 0.1)
				(type default)
			)
			(layer "B.Fab")
		)
		(fp_line
			(start -0.67945 -0.3048)
			(end -0.67945 0.3048)
			(stroke
				(width 0.1)
				(type default)
			)
			(layer "B.Fab")
		)
		(pad "1" smd circle
			(at 0.40005 0)
			(size 0 0)
			(layers "B.Cu" "B.Mask" "B.Paste")
			(net "M_BMC_DDR4_MA<1>")
		)
		(pad "2" smd circle
			(at -0.40005 0)
			(size 0 0)
			(layers "B.Cu" "B.Mask" "B.Paste")
			(net "P1V2_AUX")
		)
	)
	(footprint ""
		(layer "B.Cu")
		(at 43.163236 -65.743582 -90)
		(property "Reference" "R191"
			(at 0 0 90)
			(layer "B.SilkS")
			(hide yes)
			(effects
				(font
					(size 1.27 1.27)
				)
				(justify mirror)
			)
		)
		(property "Value" ""
			(at 0 0 90)
			(layer "B.Fab")
			(effects
				(font
					(size 1.27 1.27)
				)
				(justify mirror)
			)
		)
		(duplicate_pad_numbers_are_jumpers no)
		(fp_line
			(start -0.7874 0.4064)
			(end 0.7874 0.4064)
			(stroke
				(width 0.1524)
				(type default)
			)
			(layer "B.SilkS")
		)
		(fp_line
			(start 0.7874 0.4064)
			(end 0.7874 -0.4064)
			(stroke
				(width 0.1524)
				(type default)
			)
			(layer "B.SilkS")
		)
		(fp_line
			(start -0.7874 -0.4064)
			(end -0.7874 0.4064)
			(stroke
				(width 0.1524)
				(type default)
			)
			(layer "B.SilkS")
		)
		(fp_line
			(start 0.7874 -0.4064)
			(end -0.7874 -0.4064)
			(stroke
				(width 0.1524)
				(type default)
			)
			(layer "B.SilkS")
		)
		(fp_line
			(start -0.67945 0.3048)
			(end -0.120396 0.3048)
			(stroke
				(width 0.1)
				(type default)
			)
			(layer "B.Fab")
		)
		(fp_line
			(start -0.120396 0.3048)
			(end -0.120396 0.2794)
			(stroke
				(width 0.1)
				(type default)
			)
			(layer "B.Fab")
		)
		(fp_line
			(start 0.12065 0.3048)
			(end 0.67945 0.3048)
			(stroke
				(width 0.1)
				(type default)
			)
			(layer "B.Fab")
		)
		(fp_line
			(start 0.67945 0.3048)
			(end 0.67945 -0.305054)
			(stroke
				(width 0.1)
				(type default)
			)
			(layer "B.Fab")
		)
		(fp_line
			(start -0.120396 0.2794)
			(end 0.12065 0.2794)
			(stroke
				(width 0.1)
				(type default)
			)
			(layer "B.Fab")
		)
		(fp_line
			(start 0.12065 0.2794)
			(end 0.12065 0.3048)
			(stroke
				(width 0.1)
				(type default)
			)
			(layer "B.Fab")
		)
		(fp_line
			(start -0.12065 -0.2794)
			(end -0.12065 -0.3048)
			(stroke
				(width 0.1)
				(type default)
			)
			(layer "B.Fab")
		)
		(fp_line
			(start 0.12065 -0.2794)
			(end -0.12065 -0.2794)
			(stroke
				(width 0.1)
				(type default)
			)
			(layer "B.Fab")
		)
		(fp_line
			(start -0.67945 -0.3048)
			(end -0.67945 0.3048)
			(stroke
				(width 0.1)
				(type default)
			)
			(layer "B.Fab")
		)
		(fp_line
			(start -0.12065 -0.3048)
			(end -0.67945 -0.3048)
			(stroke
				(width 0.1)
				(type default)
			)
			(layer "B.Fab")
		)
		(fp_line
			(start 0.12065 -0.305054)
			(end 0.12065 -0.2794)
			(stroke
				(width 0.1)
				(type default)
			)
			(layer "B.Fab")
		)
		(fp_line
			(start 0.67945 -0.305054)
			(end 0.12065 -0.305054)
			(stroke
				(width 0.1)
				(type default)
			)
			(layer "B.Fab")
		)
		(pad "1" smd circle
			(at 0.40005 0 90)
			(size 0 0)
			(layers "B.Cu" "B.Mask" "B.Paste")
			(net "P1V2_P1V0_I3C_VDDL1")
		)
		(pad "2" smd circle
			(at -0.40005 0 90)
			(size 0 0)
			(layers "B.Cu" "B.Mask" "B.Paste")
			(net "I3C2_SPD_SDA")
		)
	)
)
